(kicad_pcb
	(version 20260206)
	(generator "pcbnew")
	(generator_version "10.0")
	(general
		(thickness 1.6)
		(legacy_teardrops no)
	)
	(paper "A4")
	(title_block
		(title "04192023_DAF0TMB3IC0_F0TG_MB_C_brd_V02_OCP.brd")
		(comment 1 "Grand Teton / footprints 6818-6823 of 8354")
	)
	(layers
		(0 "F.Cu" signal "TOP")
		(4 "In1.Cu" signal "GND")
		(6 "In2.Cu" signal "IN1")
		(8 "In3.Cu" signal "GND1")
		(10 "In4.Cu" signal "IN2")
		(12 "In5.Cu" signal "GND2")
		(14 "In6.Cu" signal "IN3")
		(16 "In7.Cu" signal "GND3")
		(18 "In8.Cu" signal "VCC")
		(20 "In9.Cu" signal "VCC1")
		(22 "In10.Cu" signal "GND4")
		(24 "In11.Cu" signal "IN4")
		(26 "In12.Cu" signal "GND5")
		(28 "In13.Cu" signal "IN5")
		(30 "In14.Cu" signal "GND6")
		(32 "In15.Cu" signal "IN6")
		(34 "In16.Cu" signal "GND7")
		(2 "B.Cu" signal "BOTTOM")
		(9 "F.Adhes" user "F.Adhesive")
		(11 "B.Adhes" user "B.Adhesive")
		(13 "F.Paste" user "Package Geometry/Pastemask Top")
		(15 "B.Paste" user "Package Geometry/Pastemask Bottom")
		(5 "F.SilkS" user "Ref Des/Silkscreen Top")
		(7 "B.SilkS" user "Ref Des/Silkscreen Bottom")
		(1 "F.Mask" user "Board Geometry/Soldermask Top")
		(3 "B.Mask" user "Board Geometry/Soldermask Bottom")
		(17 "Dwgs.User" user "User.Drawings")
		(19 "Cmts.User" user "User.Comments")
		(21 "Eco1.User" user "User.Eco1")
		(23 "Eco2.User" user "User.Eco2")
		(25 "Edge.Cuts" user "Board Geometry/Outline")
		(27 "Margin" user)
		(31 "F.CrtYd" user "Package Geometry/Place Bound Top")
		(29 "B.CrtYd" user "Package Geometry/Place Bound Bottom")
		(35 "F.Fab" user "Ref Des/Assembly Top")
		(33 "B.Fab" user "Ref Des/Assembly Bottom")
	)
	(footprint ""
		(layer "B.Cu")
		(at 413.502856 -163.891468 -90)
		(property "Reference" "PC613_3"
			(at 0 0 90)
			(layer "B.SilkS")
			(hide yes)
			(effects
				(font
					(size 1.27 1.27)
				)
				(justify mirror)
			)
		)
		(property "Value" ""
			(at 0 0 90)
			(layer "B.Fab")
			(effects
				(font
					(size 1.27 1.27)
				)
				(justify mirror)
			)
		)
		(duplicate_pad_numbers_are_jumpers no)
		(fp_line
			(start -1.524 0.762)
			(end 1.524 0.762)
			(stroke
				(width 0.1524)
				(type default)
			)
			(layer "B.SilkS")
		)
		(fp_line
			(start 1.524 0.762)
			(end 1.524 -0.762)
			(stroke
				(width 0.1524)
				(type default)
			)
			(layer "B.SilkS")
		)
		(fp_line
			(start -1.524 -0.762)
			(end -1.524 0.762)
			(stroke
				(width 0.1524)
				(type default)
			)
			(layer "B.SilkS")
		)
		(fp_line
			(start 1.524 -0.762)
			(end -1.524 -0.762)
			(stroke
				(width 0.1524)
				(type default)
			)
			(layer "B.SilkS")
		)
		(fp_line
			(start -1.1049 0.724916)
			(end -1.1049 -0.724916)
			(stroke
				(width 0.1)
				(type default)
			)
			(layer "B.Fab")
		)
		(fp_line
			(start 1.1049 0.724916)
			(end -1.1049 0.724916)
			(stroke
				(width 0.1)
				(type default)
			)
			(layer "B.Fab")
		)
		(fp_line
			(start -1.1049 -0.724916)
			(end 1.1049 -0.724916)
			(stroke
				(width 0.1)
				(type default)
			)
			(layer "B.Fab")
		)
		(fp_line
			(start 1.1049 -0.724916)
			(end 1.1049 0.724916)
			(stroke
				(width 0.1)
				(type default)
			)
			(layer "B.Fab")
		)
		(pad "1" smd rect
			(at 0.889 0 270)
			(size 1.016 1.27)
			(layers "B.Cu" "B.Mask" "B.Paste")
			(net "SW_P12V_AUX_PVDDCR_SOC_P0_FLT")
		)
		(pad "2" smd rect
			(at -0.889 0 270)
			(size 1.016 1.27)
			(layers "B.Cu" "B.Mask" "B.Paste")
			(net "GND")
		)
	)
	(footprint ""
		(layer "B.Cu")
		(at 175.316642 -195.8594 180)
		(property "Reference" "R1707"
			(at 0 0 0)
			(layer "B.SilkS")
			(hide yes)
			(effects
				(font
					(size 1.27 1.27)
				)
				(justify mirror)
			)
		)
		(property "Value" ""
			(at 0 0 0)
			(layer "B.Fab")
			(effects
				(font
					(size 1.27 1.27)
				)
				(justify mirror)
			)
		)
		(duplicate_pad_numbers_are_jumpers no)
		(fp_line
			(start 0.7874 0.4064)
			(end 0.7874 -0.4064)
			(stroke
				(width 0.1524)
				(type default)
			)
			(layer "B.SilkS")
		)
		(fp_line
			(start 0.7874 -0.4064)
			(end -0.7874 -0.4064)
			(stroke
				(width 0.1524)
				(type default)
			)
			(layer "B.SilkS")
		)
		(fp_line
			(start -0.7874 0.4064)
			(end 0.7874 0.4064)
			(stroke
				(width 0.1524)
				(type default)
			)
			(layer "B.SilkS")
		)
		(fp_line
			(start -0.7874 -0.4064)
			(end -0.7874 0.4064)
			(stroke
				(width 0.1524)
				(type default)
			)
			(layer "B.SilkS")
		)
		(fp_line
			(start 0.67945 0.3048)
			(end 0.67945 -0.305054)
			(stroke
				(width 0.1)
				(type default)
			)
			(layer "B.Fab")
		)
		(fp_line
			(start 0.67945 -0.305054)
			(end 0.12065 -0.305054)
			(stroke
				(width 0.1)
				(type default)
			)
			(layer "B.Fab")
		)
		(fp_line
			(start 0.12065 0.3048)
			(end 0.67945 0.3048)
			(stroke
				(width 0.1)
				(type default)
			)
			(layer "B.Fab")
		)
		(fp_line
			(start 0.12065 0.2794)
			(end 0.12065 0.3048)
			(stroke
				(width 0.1)
				(type default)
			)
			(layer "B.Fab")
		)
		(fp_line
			(start 0.12065 -0.2794)
			(end -0.12065 -0.2794)
			(stroke
				(width 0.1)
				(type default)
			)
			(layer "B.Fab")
		)
		(fp_line
			(start 0.12065 -0.305054)
			(end 0.12065 -0.2794)
			(stroke
				(width 0.1)
				(type default)
			)
			(layer "B.Fab")
		)
		(fp_line
			(start -0.120396 0.3048)
			(end -0.120396 0.2794)
			(stroke
				(width 0.1)
				(type default)
			)
			(layer "B.Fab")
		)
		(fp_line
			(start -0.120396 0.2794)
			(end 0.12065 0.2794)
			(stroke
				(width 0.1)
				(type default)
			)
			(layer "B.Fab")
		)
		(fp_line
			(start -0.12065 -0.2794)
			(end -0.12065 -0.3048)
			(stroke
				(width 0.1)
				(type default)
			)
			(layer "B.Fab")
		)
		(fp_line
			(start -0.12065 -0.3048)
			(end -0.67945 -0.3048)
			(stroke
				(width 0.1)
				(type default)
			)
			(layer "B.Fab")
		)
		(fp_line
			(start -0.67945 0.3048)
			(end -0.120396 0.3048)
			(stroke
				(width 0.1)
				(type default)
			)
			(layer "B.Fab")
		)
		(fp_line
			(start -0.67945 -0.3048)
			(end -0.67945 0.3048)
			(stroke
				(width 0.1)
				(type default)
			)
			(layer "B.Fab")
		)
		(pad "1" smd circle
			(at 0.40005 0)
			(size 0 0)
			(layers "B.Cu" "B.Mask" "B.Paste")
			(net "I3C_SPD_DDRGL_CPU1_SDA")
		)
		(pad "2" smd circle
			(at -0.40005 0)
			(size 0 0)
			(layers "B.Cu" "B.Mask" "B.Paste")
			(net "I3C_SPD_DDRH_CPU1_SDA")
		)
	)
	(footprint ""
		(layer "B.Cu")
		(at 206.22133 -193.99631)
		(property "Reference" "C180"
			(at 0 0 0)
			(layer "B.SilkS")
			(hide yes)
			(effects
				(font
					(size 1.27 1.27)
				)
				(justify mirror)
			)
		)
		(property "Value" ""
			(at 0 0 0)
			(layer "B.Fab")
			(effects
				(font
					(size 1.27 1.27)
				)
				(justify mirror)
			)
		)
		(duplicate_pad_numbers_are_jumpers no)
		(fp_line
			(start -0.7874 -0.4064)
			(end -0.7874 0.4064)
			(stroke
				(width 0.1524)
				(type default)
			)
			(layer "B.SilkS")
		)
		(fp_line
			(start -0.7874 0.4064)
			(end 0.7874 0.4064)
			(stroke
				(width 0.1524)
				(type default)
			)
			(layer "B.SilkS")
		)
		(fp_line
			(start 0.7874 -0.4064)
			(end -0.7874 -0.4064)
			(stroke
				(width 0.1524)
				(type default)
			)
			(layer "B.SilkS")
		)
		(fp_line
			(start 0.7874 0.4064)
			(end 0.7874 -0.4064)
			(stroke
				(width 0.1524)
				(type default)
			)
			(layer "B.SilkS")
		)
		(fp_line
			(start -0.67945 -0.3048)
			(end -0.67945 0.3048)
			(stroke
				(width 0.1)
				(type default)
			)
			(layer "B.Fab")
		)
		(fp_line
			(start -0.67945 0.3048)
			(end -0.120396 0.3048)
			(stroke
				(width 0.1)
				(type default)
			)
			(layer "B.Fab")
		)
		(fp_line
			(start -0.12065 -0.3048)
			(end -0.67945 -0.3048)
			(stroke
				(width 0.1)
				(type default)
			)
			(layer "B.Fab")
		)
		(fp_line
			(start -0.12065 -0.2794)
			(end -0.12065 -0.3048)
			(stroke
				(width 0.1)
				(type default)
			)
			(layer "B.Fab")
		)
		(fp_line
			(start -0.120396 0.2794)
			(end 0.12065 0.2794)
			(stroke
				(width 0.1)
				(type default)
			)
			(layer "B.Fab")
		)
		(fp_line
			(start -0.120396 0.3048)
			(end -0.120396 0.2794)
			(stroke
				(width 0.1)
				(type default)
			)
			(layer "B.Fab")
		)
		(fp_line
			(start 0.12065 -0.305054)
			(end 0.12065 -0.2794)
			(stroke
				(width 0.1)
				(type default)
			)
			(layer "B.Fab")
		)
		(fp_line
			(start 0.12065 -0.2794)
			(end -0.12065 -0.2794)
			(stroke
				(width 0.1)
				(type default)
			)
			(layer "B.Fab")
		)
		(fp_line
			(start 0.12065 0.2794)
			(end 0.12065 0.3048)
			(stroke
				(width 0.1)
				(type default)
			)
			(layer "B.Fab")
		)
		(fp_line
			(start 0.12065 0.3048)
			(end 0.67945 0.3048)
			(stroke
				(width 0.1)
				(type default)
			)
			(layer "B.Fab")
		)
		(fp_line
			(start 0.67945 -0.305054)
			(end 0.12065 -0.305054)
			(stroke
				(width 0.1)
				(type default)
			)
			(layer "B.Fab")
		)
		(fp_line
			(start 0.67945 0.3048)
			(end 0.67945 -0.305054)
			(stroke
				(width 0.1)
				(type default)
			)
			(layer "B.Fab")
		)
		(pad "1" smd circle
			(at 0.40005 0 180)
			(size 0 0)
			(layers "B.Cu" "B.Mask" "B.Paste")
			(net "P3V3_AUX")
		)
		(pad "2" smd circle
			(at -0.40005 0 180)
			(size 0 0)
			(layers "B.Cu" "B.Mask" "B.Paste")
			(net "GND")
		)
	)
	(footprint ""
		(layer "B.Cu")
		(at 110.16234 -62.01791 90)
		(property "Reference" "R6223"
			(at 0 0 90)
			(layer "B.SilkS")
			(hide yes)
			(effects
				(font
					(size 1.27 1.27)
				)
				(justify mirror)
			)
		)
		(property "Value" ""
			(at 0 0 90)
			(layer "B.Fab")
			(effects
				(font
					(size 1.27 1.27)
				)
				(justify mirror)
			)
		)
		(duplicate_pad_numbers_are_jumpers no)
		(fp_line
			(start 0.7874 -0.4064)
			(end -0.7874 -0.4064)
			(stroke
				(width 0.1524)
				(type default)
			)
			(layer "B.SilkS")
		)
		(fp_line
			(start -0.7874 -0.4064)
			(end -0.7874 0.4064)
			(stroke
				(width 0.1524)
				(type default)
			)
			(layer "B.SilkS")
		)
		(fp_line
			(start 0.7874 0.4064)
			(end 0.7874 -0.4064)
			(stroke
				(width 0.1524)
				(type default)
			)
			(layer "B.SilkS")
		)
		(fp_line
			(start -0.7874 0.4064)
			(end 0.7874 0.4064)
			(stroke
				(width 0.1524)
				(type default)
			)
			(layer "B.SilkS")
		)
		(fp_line
			(start 0.67945 -0.305054)
			(end 0.12065 -0.305054)
			(stroke
				(width 0.1)
				(type default)
			)
			(layer "B.Fab")
		)
		(fp_line
			(start 0.12065 -0.305054)
			(end 0.12065 -0.2794)
			(stroke
				(width 0.1)
				(type default)
			)
			(layer "B.Fab")
		)
		(fp_line
			(start -0.12065 -0.3048)
			(end -0.67945 -0.3048)
			(stroke
				(width 0.1)
				(type default)
			)
			(layer "B.Fab")
		)
		(fp_line
			(start -0.67945 -0.3048)
			(end -0.67945 0.3048)
			(stroke
				(width 0.1)
				(type default)
			)
			(layer "B.Fab")
		)
		(fp_line
			(start 0.12065 -0.2794)
			(end -0.12065 -0.2794)
			(stroke
				(width 0.1)
				(type default)
			)
			(layer "B.Fab")
		)
		(fp_line
			(start -0.12065 -0.2794)
			(end -0.12065 -0.3048)
			(stroke
				(width 0.1)
				(type default)
			)
			(layer "B.Fab")
		)
		(fp_line
			(start 0.12065 0.2794)
			(end 0.12065 0.3048)
			(stroke
				(width 0.1)
				(type default)
			)
			(layer "B.Fab")
		)
		(fp_line
			(start -0.120396 0.2794)
			(end 0.12065 0.2794)
			(stroke
				(width 0.1)
				(type default)
			)
			(layer "B.Fab")
		)
		(fp_line
			(start 0.67945 0.3048)
			(end 0.67945 -0.305054)
			(stroke
				(width 0.1)
				(type default)
			)
			(layer "B.Fab")
		)
		(fp_line
			(start 0.12065 0.3048)
			(end 0.67945 0.3048)
			(stroke
				(width 0.1)
				(type default)
			)
			(layer "B.Fab")
		)
		(fp_line
			(start -0.120396 0.3048)
			(end -0.120396 0.2794)
			(stroke
				(width 0.1)
				(type default)
			)
			(layer "B.Fab")
		)
		(fp_line
			(start -0.67945 0.3048)
			(end -0.120396 0.3048)
			(stroke
				(width 0.1)
				(type default)
			)
			(layer "B.Fab")
		)
		(pad "1" smd circle
			(at 0.40005 0 270)
			(size 0 0)
			(layers "B.Cu" "B.Mask" "B.Paste")
			(net "PD_USB_CPU0_WP")
		)
		(pad "2" smd circle
			(at -0.40005 0 270)
			(size 0 0)
			(layers "B.Cu" "B.Mask" "B.Paste")
			(net "GND")
		)
	)
	(footprint ""
		(layer "B.Cu")
		(at 406.698958 -329.942952 180)
		(property "Reference" "R444"
			(at 0 0 0)
			(layer "B.SilkS")
			(hide yes)
			(effects
				(font
					(size 1.27 1.27)
				)
				(justify mirror)
			)
		)
		(property "Value" ""
			(at 0 0 0)
			(layer "B.Fab")
			(effects
				(font
					(size 1.27 1.27)
				)
				(justify mirror)
			)
		)
		(duplicate_pad_numbers_are_jumpers no)
		(fp_line
			(start 0.7874 0.4064)
			(end 0.7874 -0.4064)
			(stroke
				(width 0.1524)
				(type default)
			)
			(layer "B.SilkS")
		)
		(fp_line
			(start 0.7874 -0.4064)
			(end -0.7874 -0.4064)
			(stroke
				(width 0.1524)
				(type default)
			)
			(layer "B.SilkS")
		)
		(fp_line
			(start -0.7874 0.4064)
			(end 0.7874 0.4064)
			(stroke
				(width 0.1524)
				(type default)
			)
			(layer "B.SilkS")
		)
		(fp_line
			(start -0.7874 -0.4064)
			(end -0.7874 0.4064)
			(stroke
				(width 0.1524)
				(type default)
			)
			(layer "B.SilkS")
		)
		(fp_line
			(start 0.67945 0.3048)
			(end 0.67945 -0.305054)
			(stroke
				(width 0.1)
				(type default)
			)
			(layer "B.Fab")
		)
		(fp_line
			(start 0.67945 -0.305054)
			(end 0.12065 -0.305054)
			(stroke
				(width 0.1)
				(type default)
			)
			(layer "B.Fab")
		)
		(fp_line
			(start 0.12065 0.3048)
			(end 0.67945 0.3048)
			(stroke
				(width 0.1)
				(type default)
			)
			(layer "B.Fab")
		)
		(fp_line
			(start 0.12065 0.2794)
			(end 0.12065 0.3048)
			(stroke
				(width 0.1)
				(type default)
			)
			(layer "B.Fab")
		)
		(fp_line
			(start 0.12065 -0.2794)
			(end -0.12065 -0.2794)
			(stroke
				(width 0.1)
				(type default)
			)
			(layer "B.Fab")
		)
		(fp_line
			(start 0.12065 -0.305054)
			(end 0.12065 -0.2794)
			(stroke
				(width 0.1)
				(type default)
			)
			(layer "B.Fab")
		)
		(fp_line
			(start -0.120396 0.3048)
			(end -0.120396 0.2794)
			(stroke
				(width 0.1)
				(type default)
			)
			(layer "B.Fab")
		)
		(fp_line
			(start -0.120396 0.2794)
			(end 0.12065 0.2794)
			(stroke
				(width 0.1)
				(type default)
			)
			(layer "B.Fab")
		)
		(fp_line
			(start -0.12065 -0.2794)
			(end -0.12065 -0.3048)
			(stroke
				(width 0.1)
				(type default)
			)
			(layer "B.Fab")
		)
		(fp_line
			(start -0.12065 -0.3048)
			(end -0.67945 -0.3048)
			(stroke
				(width 0.1)
				(type default)
			)
			(layer "B.Fab")
		)
		(fp_line
			(start -0.67945 0.3048)
			(end -0.120396 0.3048)
			(stroke
				(width 0.1)
				(type default)
			)
			(layer "B.Fab")
		)
		(fp_line
			(start -0.67945 -0.3048)
			(end -0.67945 0.3048)
			(stroke
				(width 0.1)
				(type default)
			)
			(layer "B.Fab")
		)
		(pad "1" smd circle
			(at 0.40005 0)
			(size 0 0)
			(layers "B.Cu" "B.Mask" "B.Paste")
			(net "FM_SMM_CRASHDUMP")
		)
		(pad "2" smd circle
			(at -0.40005 0)
			(size 0 0)
			(layers "B.Cu" "B.Mask" "B.Paste")
			(net "PVDD18_S5_P0")
		)
	)
	(footprint ""
		(layer "B.Cu")
		(at 50.586386 -190.821564 180)
		(property "Reference" "R102"
			(at 0 0 0)
			(layer "B.SilkS")
			(hide yes)
			(effects
				(font
					(size 1.27 1.27)
				)
				(justify mirror)
			)
		)
		(property "Value" ""
			(at 0 0 0)
			(layer "B.Fab")
			(effects
				(font
					(size 1.27 1.27)
				)
				(justify mirror)
			)
		)
		(duplicate_pad_numbers_are_jumpers no)
		(fp_line
			(start 0.7874 0.4064)
			(end 0.7874 -0.4064)
			(stroke
				(width 0.1524)
				(type default)
			)
			(layer "B.SilkS")
		)
		(fp_line
			(start 0.7874 -0.4064)
			(end -0.7874 -0.4064)
			(stroke
				(width 0.1524)
				(type default)
			)
			(layer "B.SilkS")
		)
		(fp_line
			(start -0.7874 0.4064)
			(end 0.7874 0.4064)
			(stroke
				(width 0.1524)
				(type default)
			)
			(layer "B.SilkS")
		)
		(fp_line
			(start -0.7874 -0.4064)
			(end -0.7874 0.4064)
			(stroke
				(width 0.1524)
				(type default)
			)
			(layer "B.SilkS")
		)
		(fp_line
			(start 0.67945 0.3048)
			(end 0.67945 -0.305054)
			(stroke
				(width 0.1)
				(type default)
			)
			(layer "B.Fab")
		)
		(fp_line
			(start 0.67945 -0.305054)
			(end 0.12065 -0.305054)
			(stroke
				(width 0.1)
				(type default)
			)
			(layer "B.Fab")
		)
		(fp_line
			(start 0.12065 0.3048)
			(end 0.67945 0.3048)
			(stroke
				(width 0.1)
				(type default)
			)
			(layer "B.Fab")
		)
		(fp_line
			(start 0.12065 0.2794)
			(end 0.12065 0.3048)
			(stroke
				(width 0.1)
				(type default)
			)
			(layer "B.Fab")
		)
		(fp_line
			(start 0.12065 -0.2794)
			(end -0.12065 -0.2794)
			(stroke
				(width 0.1)
				(type default)
			)
			(layer "B.Fab")
		)
		(fp_line
			(start 0.12065 -0.305054)
			(end 0.12065 -0.2794)
			(stroke
				(width 0.1)
				(type default)
			)
			(layer "B.Fab")
		)
		(fp_line
			(start -0.120396 0.3048)
			(end -0.120396 0.2794)
			(stroke
				(width 0.1)
				(type default)
			)
			(layer "B.Fab")
		)
		(fp_line
			(start -0.120396 0.2794)
			(end 0.12065 0.2794)
			(stroke
				(width 0.1)
				(type default)
			)
			(layer "B.Fab")
		)
		(fp_line
			(start -0.12065 -0.2794)
			(end -0.12065 -0.3048)
			(stroke
				(width 0.1)
				(type default)
			)
			(layer "B.Fab")
		)
		(fp_line
			(start -0.12065 -0.3048)
			(end -0.67945 -0.3048)
			(stroke
				(width 0.1)
				(type default)
			)
			(layer "B.Fab")
		)
		(fp_line
			(start -0.67945 0.3048)
			(end -0.120396 0.3048)
			(stroke
				(width 0.1)
				(type default)
			)
			(layer "B.Fab")
		)
		(fp_line
			(start -0.67945 -0.3048)
			(end -0.67945 0.3048)
			(stroke
				(width 0.1)
				(type default)
			)
			(layer "B.Fab")
		)
		(pad "1" smd circle
			(at 0.40005 0)
			(size 0 0)
			(layers "B.Cu" "B.Mask" "B.Paste")
			(net "P3V3")
		)
		(pad "2" smd circle
			(at -0.40005 0)
			(size 0 0)
			(layers "B.Cu" "B.Mask" "B.Paste")
			(net "PWRGD_CHAF_CPU1")
		)
	)
)
